(kicad_pcb
	(version 20260206)
	(generator "pcbnew")
	(generator_version "10.0")
	(general
		(thickness 1.6)
		(legacy_teardrops no)
	)
	(paper "A4")
	(title_block
		(title "Wiwynn_Tioga_Pass_MB.brd")
		(comment 1 "Tioga Pass / footprints 145-151 of 4770")
	)
	(layers
		(0 "F.Cu" signal "TOP")
		(4 "In1.Cu" signal "L2GND")
		(6 "In2.Cu" signal "L3")
		(8 "In3.Cu" signal "L4GND")
		(10 "In4.Cu" signal "L5")
		(12 "In5.Cu" signal "L6GND")
		(14 "In6.Cu" signal "L7VCC")
		(16 "In7.Cu" signal "L8VCC")
		(18 "In8.Cu" signal "L9GND")
		(20 "In9.Cu" signal "L10")
		(22 "In10.Cu" signal "L11GND")
		(24 "In11.Cu" signal "L12")
		(26 "In12.Cu" signal "L13GND")
		(2 "B.Cu" signal "BOTTOM")
		(9 "F.Adhes" user "F.Adhesive")
		(11 "B.Adhes" user "B.Adhesive")
		(13 "F.Paste" user "Package Geometry/Pastemask Top")
		(15 "B.Paste" user "Package Geometry/Pastemask Bottom")
		(5 "F.SilkS" user "Ref Des/Silkscreen Top")
		(7 "B.SilkS" user "Ref Des/Silkscreen Bottom")
		(1 "F.Mask" user "Board Geometry/Soldermask Top")
		(3 "B.Mask" user "Board Geometry/Soldermask Bottom")
		(17 "Dwgs.User" user "User.Drawings")
		(19 "Cmts.User" user "User.Comments")
		(21 "Eco1.User" user "User.Eco1")
		(23 "Eco2.User" user "User.Eco2")
		(25 "Edge.Cuts" user "Board Geometry/Outline")
		(27 "Margin" user)
		(31 "F.CrtYd" user "Package Geometry/Place Bound Top")
		(29 "B.CrtYd" user "Package Geometry/Place Bound Bottom")
		(35 "F.Fab" user "Ref Des/Assembly Top")
		(33 "B.Fab" user "Ref Des/Assembly Bottom")
	)
	(footprint ""
		(layer "F.Cu")
		(at 349.123 -12.827 90)
		(property "Reference" "R7G10"
			(at 0 0 90)
			(layer "F.SilkS")
			(hide yes)
			(effects
				(font
					(size 1.27 1.27)
				)
			)
		)
		(property "Value" ""
			(at 0 0 90)
			(layer "F.Fab")
			(effects
				(font
					(size 1.27 1.27)
				)
			)
		)
		(duplicate_pad_numbers_are_jumpers no)
		(fp_poly
			(pts
				(xy -0.2794 -0.1016) (xy 0.2794 -0.1016) (xy 0.2794 0.9906) (xy -0.2794 0.9906)
			)
			(stroke
				(width 0)
				(type default)
			)
			(fill no)
			(layer "F.CrtYd")
		)
		(fp_line
			(start 0.2794 -0.1016)
			(end -0.2794 -0.1016)
			(stroke
				(width 0.1)
				(type default)
			)
			(layer "F.Fab")
		)
		(fp_line
			(start -0.2794 -0.1016)
			(end -0.2794 0.9906)
			(stroke
				(width 0.1)
				(type default)
			)
			(layer "F.Fab")
		)
		(fp_line
			(start 0.2794 0.9906)
			(end 0.2794 -0.1016)
			(stroke
				(width 0.1)
				(type default)
			)
			(layer "F.Fab")
		)
		(fp_line
			(start -0.2794 0.9906)
			(end 0.2794 0.9906)
			(stroke
				(width 0.1)
				(type default)
			)
			(layer "F.Fab")
		)
		(pad "1" smd rect
			(at 0 0 90)
			(size 0.508 0.508)
			(layers "F.Cu" "F.Mask" "F.Paste")
			(net "VR_PVDDQ_ABC_XADDR2")
		)
		(pad "2" smd rect
			(at 0 0.889 90)
			(size 0.508 0.508)
			(layers "F.Cu" "F.Mask" "F.Paste")
			(net "GND")
		)
		(zone
			(layer "F.Cu")
			(hatch none 0.5)
			(connect_pads
				(clearance 0)
			)
			(min_thickness 0.25)
			(keepout
				(tracks allowed)
				(vias not_allowed)
				(pads allowed)
				(copperpour not_allowed)
				(footprints allowed)
			)
			(placement
				(enabled no)
				(sheetname "")
			)
			(fill
				(thermal_gap 0.5)
				(thermal_bridge_width 0.5)
				(island_removal_mode 0)
			)
			(polygon
				(pts
					(xy 349.377 -12.573) (xy 349.377 -13.081) (xy 349.758 -13.081) (xy 349.758 -12.573)
				)
			)
		)
		(zone
			(layer "F.Cu")
			(hatch none 0.5)
			(connect_pads
				(clearance 0)
			)
			(min_thickness 0.25)
			(keepout
				(tracks not_allowed)
				(vias allowed)
				(pads allowed)
				(copperpour not_allowed)
				(footprints allowed)
			)
			(placement
				(enabled no)
				(sheetname "")
			)
			(fill
				(thermal_gap 0.5)
				(thermal_bridge_width 0.5)
				(island_removal_mode 0)
			)
			(polygon
				(pts
					(xy 349.758 -12.573) (xy 349.758 -13.081) (xy 349.377 -13.081) (xy 349.377 -12.573)
				)
			)
		)
	)
	(footprint ""
		(layer "F.Cu")
		(at 413.521652 -135.636)
		(property "Reference" "R8A13"
			(at 0 0 0)
			(layer "F.SilkS")
			(hide yes)
			(effects
				(font
					(size 1.27 1.27)
				)
			)
		)
		(property "Value" ""
			(at 0 0 0)
			(layer "F.Fab")
			(effects
				(font
					(size 1.27 1.27)
				)
			)
		)
		(duplicate_pad_numbers_are_jumpers no)
		(fp_poly
			(pts
				(xy -0.2794 -0.1016) (xy 0.2794 -0.1016) (xy 0.2794 0.9906) (xy -0.2794 0.9906)
			)
			(stroke
				(width 0)
				(type default)
			)
			(fill no)
			(layer "F.CrtYd")
		)
		(fp_line
			(start -0.2794 -0.1016)
			(end -0.2794 0.9906)
			(stroke
				(width 0.1)
				(type default)
			)
			(layer "F.Fab")
		)
		(fp_line
			(start -0.2794 0.9906)
			(end 0.2794 0.9906)
			(stroke
				(width 0.1)
				(type default)
			)
			(layer "F.Fab")
		)
		(fp_line
			(start 0.2794 -0.1016)
			(end -0.2794 -0.1016)
			(stroke
				(width 0.1)
				(type default)
			)
			(layer "F.Fab")
		)
		(fp_line
			(start 0.2794 0.9906)
			(end 0.2794 -0.1016)
			(stroke
				(width 0.1)
				(type default)
			)
			(layer "F.Fab")
		)
		(pad "1" smd rect
			(at 0 0)
			(size 0.508 0.508)
			(layers "F.Cu" "F.Mask" "F.Paste")
			(net "P1V05_PCH_STBY")
		)
		(pad "2" smd rect
			(at 0 0.889)
			(size 0.508 0.508)
			(layers "F.Cu" "F.Mask" "F.Paste")
			(net "XDP_TDI")
		)
		(zone
			(layer "F.Cu")
			(hatch none 0.5)
			(connect_pads
				(clearance 0)
			)
			(min_thickness 0.25)
			(keepout
				(tracks allowed)
				(vias not_allowed)
				(pads allowed)
				(copperpour not_allowed)
				(footprints allowed)
			)
			(placement
				(enabled no)
				(sheetname "")
			)
			(fill
				(thermal_gap 0.5)
				(thermal_bridge_width 0.5)
				(island_removal_mode 0)
			)
			(polygon
				(pts
					(xy 413.267652 -135.382) (xy 413.775652 -135.382) (xy 413.775652 -135.001) (xy 413.267652 -135.001)
				)
			)
		)
		(zone
			(layer "F.Cu")
			(hatch none 0.5)
			(connect_pads
				(clearance 0)
			)
			(min_thickness 0.25)
			(keepout
				(tracks not_allowed)
				(vias allowed)
				(pads allowed)
				(copperpour not_allowed)
				(footprints allowed)
			)
			(placement
				(enabled no)
				(sheetname "")
			)
			(fill
				(thermal_gap 0.5)
				(thermal_bridge_width 0.5)
				(island_removal_mode 0)
			)
			(polygon
				(pts
					(xy 413.267652 -135.001) (xy 413.775652 -135.001) (xy 413.775652 -135.382) (xy 413.267652 -135.382)
				)
			)
		)
	)
	(footprint ""
		(layer "F.Cu")
		(at 364.617 -112.395 90)
		(property "Reference" "C7B28"
			(at 0 0 90)
			(layer "F.SilkS")
			(hide yes)
			(effects
				(font
					(size 1.27 1.27)
				)
			)
		)
		(property "Value" ""
			(at 0 0 90)
			(layer "F.Fab")
			(effects
				(font
					(size 1.27 1.27)
				)
			)
		)
		(duplicate_pad_numbers_are_jumpers no)
		(fp_poly
			(pts
				(xy 0.3048 -0.1016) (xy 0.3048 0.9906) (xy -0.3048 0.9906) (xy -0.3048 -0.1016)
			)
			(stroke
				(width 0)
				(type default)
			)
			(fill no)
			(layer "F.CrtYd")
		)
		(fp_line
			(start 0.3048 -0.1016)
			(end -0.3048 -0.1016)
			(stroke
				(width 0.1)
				(type default)
			)
			(layer "F.Fab")
		)
		(fp_line
			(start -0.3048 -0.1016)
			(end -0.3048 0.9906)
			(stroke
				(width 0.1)
				(type default)
			)
			(layer "F.Fab")
		)
		(fp_line
			(start 0.3048 0.9906)
			(end 0.3048 -0.1016)
			(stroke
				(width 0.1)
				(type default)
			)
			(layer "F.Fab")
		)
		(fp_line
			(start -0.3048 0.9906)
			(end 0.3048 0.9906)
			(stroke
				(width 0.1)
				(type default)
			)
			(layer "F.Fab")
		)
		(pad "1" smd rect
			(at 0 0 90)
			(size 0.508 0.508)
			(layers "F.Cu" "F.Mask" "F.Paste")
			(net "DMI_CPU0_PCH_TX_DP<1>")
		)
		(pad "2" smd rect
			(at 0 0.889 90)
			(size 0.508 0.508)
			(layers "F.Cu" "F.Mask" "F.Paste")
			(net "DMI_CPU0_PCH_TX_C_DP<1>")
		)
		(zone
			(layer "F.Cu")
			(hatch none 0.5)
			(connect_pads
				(clearance 0)
			)
			(min_thickness 0.25)
			(keepout
				(tracks allowed)
				(vias not_allowed)
				(pads allowed)
				(copperpour not_allowed)
				(footprints allowed)
			)
			(placement
				(enabled no)
				(sheetname "")
			)
			(fill
				(thermal_gap 0.5)
				(thermal_bridge_width 0.5)
				(island_removal_mode 0)
			)
			(polygon
				(pts
					(xy 364.871 -112.141) (xy 364.871 -112.649) (xy 365.252 -112.649) (xy 365.252 -112.141)
				)
			)
		)
		(zone
			(layer "F.Cu")
			(hatch none 0.5)
			(connect_pads
				(clearance 0)
			)
			(min_thickness 0.25)
			(keepout
				(tracks not_allowed)
				(vias allowed)
				(pads allowed)
				(copperpour not_allowed)
				(footprints allowed)
			)
			(placement
				(enabled no)
				(sheetname "")
			)
			(fill
				(thermal_gap 0.5)
				(thermal_bridge_width 0.5)
				(island_removal_mode 0)
			)
			(polygon
				(pts
					(xy 365.252 -112.141) (xy 365.252 -112.649) (xy 364.871 -112.649) (xy 364.871 -112.141)
				)
			)
		)
	)
	(footprint ""
		(layer "F.Cu")
		(at 25.0698 -77.1906 90)
		(property "Reference" "Q1D2"
			(at -4.1402 1.60147 90)
			(unlocked yes)
			(layer "F.SilkS")
			(effects
				(font
					(size 0.7874 0.5842)
					(thickness 0.1524)
				)
				(justify left)
			)
		)
		(property "Value" ""
			(at 0 0 90)
			(layer "F.Fab")
			(effects
				(font
					(size 1.27 1.27)
				)
			)
		)
		(duplicate_pad_numbers_are_jumpers no)
		(fp_line
			(start 1.778 -0.5715)
			(end 1.778 0.3175)
			(stroke
				(width 0.1524)
				(type default)
			)
			(layer "F.SilkS")
		)
		(fp_line
			(start 0.9525 -0.5715)
			(end 1.778 -0.5715)
			(stroke
				(width 0.1524)
				(type default)
			)
			(layer "F.SilkS")
		)
		(fp_line
			(start 0.381 0.635)
			(end 0.381 1.27)
			(stroke
				(width 0.1524)
				(type default)
			)
			(layer "F.SilkS")
		)
		(fp_line
			(start 1.778 2.4765)
			(end 1.778 1.5875)
			(stroke
				(width 0.1524)
				(type default)
			)
			(layer "F.SilkS")
		)
		(fp_line
			(start 0.9525 2.4765)
			(end 1.778 2.4765)
			(stroke
				(width 0.1524)
				(type default)
			)
			(layer "F.SilkS")
		)
		(fp_circle
			(center -0.9525 -0.9271)
			(end -0.9525 -0.8001)
			(stroke
				(width 0.254)
				(type default)
			)
			(fill no)
			(layer "F.SilkS")
		)
		(fp_poly
			(pts
				(xy 1.778 2.4765) (xy 0.381 2.4765) (xy 0.381 -0.5715) (xy 1.778 -0.5715)
			)
			(stroke
				(width 0)
				(type default)
			)
			(fill no)
			(layer "F.CrtYd")
		)
		(fp_line
			(start 1.778 -0.5715)
			(end 0.381 -0.5715)
			(stroke
				(width 0.1)
				(type default)
			)
			(layer "F.Fab")
		)
		(fp_line
			(start 0.381 -0.5715)
			(end 0.381 2.4765)
			(stroke
				(width 0.1)
				(type default)
			)
			(layer "F.Fab")
		)
		(fp_line
			(start 1.778 2.4765)
			(end 1.778 -0.5715)
			(stroke
				(width 0.1)
				(type default)
			)
			(layer "F.Fab")
		)
		(fp_line
			(start 0.381 2.4765)
			(end 1.778 2.4765)
			(stroke
				(width 0.1)
				(type default)
			)
			(layer "F.Fab")
		)
		(fp_circle
			(center -0.9525 -0.9271)
			(end -0.9525 -0.8001)
			(stroke
				(width 0.254)
				(type default)
			)
			(fill no)
			(layer "F.Fab")
		)
		(pad "1" smd rect
			(at 0 0 90)
			(size 1.143 0.508)
			(layers "F.Cu" "F.Mask" "F.Paste")
			(net "FM_OC_DETECT_EN_N")
		)
		(pad "2" smd rect
			(at 0 1.905 90)
			(size 1.143 0.508)
			(layers "F.Cu" "F.Mask" "F.Paste")
			(net "GND")
		)
		(pad "3" smd rect
			(at 2.159 0.9525 90)
			(size 1.143 0.508)
			(layers "F.Cu" "F.Mask" "F.Paste")
			(net "FM_OC_DETECT_EN")
		)
	)
	(footprint ""
		(layer "F.Cu")
		(at 379.725428 -154.266646)
		(property "Reference" "C7A7"
			(at 0 0 0)
			(layer "F.SilkS")
			(hide yes)
			(effects
				(font
					(size 1.27 1.27)
				)
			)
		)
		(property "Value" ""
			(at 0 0 0)
			(layer "F.Fab")
			(effects
				(font
					(size 1.27 1.27)
				)
			)
		)
		(duplicate_pad_numbers_are_jumpers no)
		(fp_poly
			(pts
				(xy 0.3048 -0.1016) (xy 0.3048 0.9906) (xy -0.3048 0.9906) (xy -0.3048 -0.1016)
			)
			(stroke
				(width 0)
				(type default)
			)
			(fill no)
			(layer "F.CrtYd")
		)
		(fp_line
			(start -0.3048 -0.1016)
			(end -0.3048 0.9906)
			(stroke
				(width 0.1)
				(type default)
			)
			(layer "F.Fab")
		)
		(fp_line
			(start -0.3048 0.9906)
			(end 0.3048 0.9906)
			(stroke
				(width 0.1)
				(type default)
			)
			(layer "F.Fab")
		)
		(fp_line
			(start 0.3048 -0.1016)
			(end -0.3048 -0.1016)
			(stroke
				(width 0.1)
				(type default)
			)
			(layer "F.Fab")
		)
		(fp_line
			(start 0.3048 0.9906)
			(end 0.3048 -0.1016)
			(stroke
				(width 0.1)
				(type default)
			)
			(layer "F.Fab")
		)
		(pad "1" smd rect
			(at 0 0)
			(size 0.508 0.508)
			(layers "F.Cu" "F.Mask" "F.Paste")
			(net "VR_FET_SW_P12V_STBY_PVDDQ_DEF")
		)
		(pad "2" smd rect
			(at 0 0.889)
			(size 0.508 0.508)
			(layers "F.Cu" "F.Mask" "F.Paste")
			(net "GND")
		)
		(zone
			(layer "F.Cu")
			(hatch none 0.5)
			(connect_pads
				(clearance 0)
			)
			(min_thickness 0.25)
			(keepout
				(tracks allowed)
				(vias not_allowed)
				(pads allowed)
				(copperpour not_allowed)
				(footprints allowed)
			)
			(placement
				(enabled no)
				(sheetname "")
			)
			(fill
				(thermal_gap 0.5)
				(thermal_bridge_width 0.5)
				(island_removal_mode 0)
			)
			(polygon
				(pts
					(xy 379.471428 -154.012646) (xy 379.979428 -154.012646) (xy 379.979428 -153.631646) (xy 379.471428 -153.631646)
				)
			)
		)
		(zone
			(layer "F.Cu")
			(hatch none 0.5)
			(connect_pads
				(clearance 0)
			)
			(min_thickness 0.25)
			(keepout
				(tracks not_allowed)
				(vias allowed)
				(pads allowed)
				(copperpour not_allowed)
				(footprints allowed)
			)
			(placement
				(enabled no)
				(sheetname "")
			)
			(fill
				(thermal_gap 0.5)
				(thermal_bridge_width 0.5)
				(island_removal_mode 0)
			)
			(polygon
				(pts
					(xy 379.471428 -153.631646) (xy 379.979428 -153.631646) (xy 379.979428 -154.012646) (xy 379.471428 -154.012646)
				)
			)
		)
	)
	(footprint ""
		(layer "F.Cu")
		(at 385.30784 -89.55532 180)
		(property "Reference" "R7W15"
			(at -0.8382 -0.67818 180)
			(unlocked yes)
			(layer "F.SilkS")
			(effects
				(font
					(size 0.4064 0.254)
					(thickness 0.1524)
				)
				(justify left)
			)
		)
		(property "Value" ""
			(at 0 0 180)
			(layer "F.Fab")
			(effects
				(font
					(size 1.27 1.27)
				)
			)
		)
		(duplicate_pad_numbers_are_jumpers no)
		(fp_poly
			(pts
				(xy -0.2794 -0.1016) (xy 0.2794 -0.1016) (xy 0.2794 0.9906) (xy -0.2794 0.9906)
			)
			(stroke
				(width 0)
				(type default)
			)
			(fill no)
			(layer "F.CrtYd")
		)
		(fp_line
			(start 0.2794 0.9906)
			(end 0.2794 -0.1016)
			(stroke
				(width 0.1)
				(type default)
			)
			(layer "F.Fab")
		)
		(fp_line
			(start 0.2794 -0.1016)
			(end -0.2794 -0.1016)
			(stroke
				(width 0.1)
				(type default)
			)
			(layer "F.Fab")
		)
		(fp_line
			(start -0.2794 0.9906)
			(end 0.2794 0.9906)
			(stroke
				(width 0.1)
				(type default)
			)
			(layer "F.Fab")
		)
		(fp_line
			(start -0.2794 -0.1016)
			(end -0.2794 0.9906)
			(stroke
				(width 0.1)
				(type default)
			)
			(layer "F.Fab")
		)
		(pad "1" smd rect
			(at 0 0 180)
			(size 0.508 0.508)
			(layers "F.Cu" "F.Mask" "F.Paste")
			(net "FM_OCP_MEZZA_PRES")
		)
		(pad "2" smd rect
			(at 0 0.889 180)
			(size 0.508 0.508)
			(layers "F.Cu" "F.Mask" "F.Paste")
			(net "FM_OCP_MEZZA_PRES_R")
		)
		(zone
			(layer "F.Cu")
			(hatch none 0.5)
			(connect_pads
				(clearance 0)
			)
			(min_thickness 0.25)
			(keepout
				(tracks not_allowed)
				(vias allowed)
				(pads allowed)
				(copperpour not_allowed)
				(footprints allowed)
			)
			(placement
				(enabled no)
				(sheetname "")
			)
			(fill
				(thermal_gap 0.5)
				(thermal_bridge_width 0.5)
				(island_removal_mode 0)
			)
			(polygon
				(pts
					(xy 385.56184 -90.19032) (xy 385.05384 -90.19032) (xy 385.05384 -89.80932) (xy 385.56184 -89.80932)
				)
			)
		)
		(zone
			(layer "F.Cu")
			(hatch none 0.5)
			(connect_pads
				(clearance 0)
			)
			(min_thickness 0.25)
			(keepout
				(tracks allowed)
				(vias not_allowed)
				(pads allowed)
				(copperpour not_allowed)
				(footprints allowed)
			)
			(placement
				(enabled no)
				(sheetname "")
			)
			(fill
				(thermal_gap 0.5)
				(thermal_bridge_width 0.5)
				(island_removal_mode 0)
			)
			(polygon
				(pts
					(xy 385.56184 -89.80932) (xy 385.05384 -89.80932) (xy 385.05384 -90.19032) (xy 385.56184 -90.19032)
				)
			)
		)
	)
	(footprint ""
		(layer "F.Cu")
		(at 345.359228 -157.1244 90)
		(property "Reference" "RT29"
			(at 0 0 90)
			(layer "F.SilkS")
			(hide yes)
			(effects
				(font
					(size 1.27 1.27)
				)
			)
		)
		(property "Value" "*"
			(at -0.0254 -2.6289 90)
			(unlocked yes)
			(layer "F.Fab")
			(hide yes)
			(effects
				(font
					(size 1.27 1.016)
					(thickness 0.1524)
				)
			)
		)
		(property "Device Type" "1R3F-GP_RCL_GP-1R3F-GP,64.1R00A"
			(at -0.0254 -4.1529 90)
			(unlocked yes)
			(layer "F.Fab")
			(hide yes)
			(effects
				(font
					(size 1.27 1.016)
					(thickness 0.1524)
				)
			)
		)
		(duplicate_pad_numbers_are_jumpers no)
		(fp_line
			(start 0.2032 0)
			(end 0.4826 0)
			(stroke
				(width 0.2032)
				(type default)
			)
			(layer "F.SilkS")
		)
		(fp_line
			(start -0.4826 0)
			(end -0.2032 0)
			(stroke
				(width 0.2032)
				(type default)
			)
			(layer "F.SilkS")
		)
		(fp_rect
			(start -0.5842 1.3335)
			(end 0.5842 -1.3335)
			(stroke
				(width 0)
				(type default)
			)
			(fill no)
			(layer "F.CrtYd")
		)
		(fp_rect
			(start -0.5842 1.3335)
			(end 0.5842 -1.3335)
			(stroke
				(width 0)
				(type default)
			)
			(fill no)
			(layer "F.Fab")
		)
		(pad "1" smd custom
			(at 0 -0.762 90)
			(size 0.2159 0.2159)
			(layers "F.Cu" "F.Mask" "F.Paste")
			(net "VR_PVDDQ_DEF_PH1_SW_RC")
			(options
				(clearance outline)
				(anchor circle)
			)
			(primitives
				(gr_poly
					(pts
						(arc
							(start -0.3302 -0.4318)
							(mid -0.402042 -0.402042)
							(end -0.4318 -0.3302)
						)
						(arc
							(start -0.4318 0.3302)
							(mid -0.402042 0.402042)
							(end -0.3302 0.4318)
						)
						(arc
							(start 0.3302 0.4318)
							(mid 0.402042 0.402042)
							(end 0.4318 0.3302)
						)
						(arc
							(start 0.4318 -0.3302)
							(mid 0.402042 -0.402042)
							(end 0.3302 -0.4318)
						)
					)
					(width 0)
					(fill yes)
				)
			)
		)
		(pad "2" smd custom
			(at 0 0.762 90)
			(size 0.2159 0.2159)
			(layers "F.Cu" "F.Mask" "F.Paste")
			(net "GND")
			(options
				(clearance outline)
				(anchor circle)
			)
			(primitives
				(gr_poly
					(pts
						(arc
							(start -0.3302 -0.4318)
							(mid -0.402042 -0.402042)
							(end -0.4318 -0.3302)
						)
						(arc
							(start -0.4318 0.3302)
							(mid -0.402042 0.402042)
							(end -0.3302 0.4318)
						)
						(arc
							(start 0.3302 0.4318)
							(mid 0.402042 0.402042)
							(end 0.4318 0.3302)
						)
						(arc
							(start 0.4318 -0.3302)
							(mid 0.402042 -0.402042)
							(end 0.3302 -0.4318)
						)
					)
					(width 0)
					(fill yes)
				)
			)
		)
	)
)
